(kicad_pcb
	(version 20221018)
	(generator pcbnew)
	(general
    (thickness 1.656)
  )
	(paper "A4")
	(title_block
    (title "SDI-MIPI Bridge")
    (date "2023-08-09")
    (rev "1.3.4")
    (company "Antmicro")
		(comment 9 "footprints 102-111 of 190")
	)
	(layers
    (0 "F.Cu" signal)
    (1 "In1.Cu" power)
    (2 "In2.Cu" power)
    (3 "In3.Cu" signal)
    (4 "In4.Cu" signal)
    (31 "B.Cu" signal)
    (32 "B.Adhes" user "B.Adhesive")
    (33 "F.Adhes" user "F.Adhesive")
    (34 "B.Paste" user)
    (35 "F.Paste" user)
    (36 "B.SilkS" user "B.Silkscreen")
    (37 "F.SilkS" user "F.Silkscreen")
    (38 "B.Mask" user)
    (39 "F.Mask" user)
    (40 "Dwgs.User" user "User.Drawings")
    (41 "Cmts.User" user "User.Comments")
    (42 "Eco1.User" user "User.Eco1")
    (43 "Eco2.User" user "User.Eco2")
    (44 "Edge.Cuts" user)
    (45 "Margin" user)
    (46 "B.CrtYd" user "B.Courtyard")
    (47 "F.CrtYd" user "F.Courtyard")
    (48 "B.Fab" user)
    (49 "F.Fab" user)
  )
	(footprint "sdi-mipi-bridge-footprints:C_0402_1005Metric" (layer "B.Cu")
    (at 116.5 112.9 90)
    (descr "Capacitor SMD 0402")
    (tags "capacitor SMD 0402")
    (property "Author" "Antmicro")
    (property "Dielectric" "X7R")
    (property "License" "Apache-2.0")
    (property "MPN" "GRM155R71H103KA88D")
    (property "Manufacturer" "Murata")
    (property "Sheetfile" "sdi-mipi-bridge.kicad_sch")
    (property "Sheetname" "")
    (property "Val" "10n")
    (property "Voltage" "50V")
    (property "ki_description" " ")
    (attr smd)
    (fp_text reference "C12" (at -1.1 -0.7 90) (layer "B.SilkS")
        (effects (font (size 0.7 0.7) (thickness 0.15)) (justify right bottom mirror))
    )
    (fp_text value "C_10n_0402" (at 0 -1.4 90) (layer "B.Fab") hide
        (effects (font (size 0.7 0.7) (thickness 0.15)) (justify right bottom mirror))
    )
    (fp_text user "${REFERENCE}" (at -0.932 -3.168 90) (layer "B.Fab") hide
        (effects (font (size 0.7 0.7) (thickness 0.15)) (justify right bottom mirror))
    )
    (fp_text user "Author: Antmicro" (at -0.932 -4.17 90) (layer "B.Fab") hide
        (effects (font (size 0.7 0.7) (thickness 0.15)) (justify right bottom mirror))
    )
    (fp_text user "License: Apache-2.0" (at -0.932 -5.17 90) (layer "B.Fab") hide
        (effects (font (size 0.7 0.7) (thickness 0.15)) (justify right bottom mirror))
    )
    (fp_rect (start -0.94 0.47) (end 0.94 -0.47)
      (stroke (width 0.05) (type solid)) (fill none) (layer "B.CrtYd"))
    (fp_rect (start -0.499 0.249) (end 0.499 -0.249)
      (stroke (width 0.15) (type solid)) (fill none) (layer "B.Fab"))
    (pad "1" smd roundrect (at -0.484 0 90) (size 0.59 0.64) (layers "B.Cu" "B.Paste" "B.Mask") (roundrect_rratio 0.25)
      (net 3 "GNDA") (pintype "passive"))
    (pad "2" smd roundrect (at 0.484 0 90) (size 0.59 0.64) (layers "B.Cu" "B.Paste" "B.Mask") (roundrect_rratio 0.25)
      (net 5 "+3.3VA") (pintype "passive"))
  )
	(footprint "sdi-mipi-bridge-footprints:C_0402_1005Metric" (layer "B.Cu")
    (at 116.5 115.4 90)
    (descr "Capacitor SMD 0402")
    (tags "capacitor SMD 0402")
    (property "Author" "Antmicro")
    (property "Dielectric" "X7R")
    (property "License" "Apache-2.0")
    (property "MPN" "GRM155R71H103KA88D")
    (property "Manufacturer" "Murata")
    (property "Sheetfile" "sdi-mipi-bridge.kicad_sch")
    (property "Sheetname" "")
    (property "Val" "10n")
    (property "Voltage" "50V")
    (property "ki_description" " ")
    (attr smd)
    (fp_text reference "C14" (at -1 1.3 90) (layer "B.SilkS")
        (effects (font (size 0.7 0.7) (thickness 0.15)) (justify right bottom mirror))
    )
    (fp_text value "C_10n_0402" (at 0 -1.4 90) (layer "B.Fab") hide
        (effects (font (size 0.7 0.7) (thickness 0.15)) (justify right bottom mirror))
    )
    (fp_text user "Author: Antmicro" (at -0.932 -4.17 90) (layer "B.Fab") hide
        (effects (font (size 0.7 0.7) (thickness 0.15)) (justify right bottom mirror))
    )
    (fp_text user "${REFERENCE}" (at -0.932 -3.168 90) (layer "B.Fab") hide
        (effects (font (size 0.7 0.7) (thickness 0.15)) (justify right bottom mirror))
    )
    (fp_text user "License: Apache-2.0" (at -0.932 -5.17 90) (layer "B.Fab") hide
        (effects (font (size 0.7 0.7) (thickness 0.15)) (justify right bottom mirror))
    )
    (fp_rect (start -0.94 0.47) (end 0.94 -0.47)
      (stroke (width 0.05) (type solid)) (fill none) (layer "B.CrtYd"))
    (fp_rect (start -0.499 0.249) (end 0.499 -0.249)
      (stroke (width 0.15) (type solid)) (fill none) (layer "B.Fab"))
    (pad "1" smd roundrect (at -0.484 0 90) (size 0.59 0.64) (layers "B.Cu" "B.Paste" "B.Mask") (roundrect_rratio 0.25)
      (net 3 "GNDA") (pintype "passive"))
    (pad "2" smd roundrect (at 0.484 0 90) (size 0.59 0.64) (layers "B.Cu" "B.Paste" "B.Mask") (roundrect_rratio 0.25)
      (net 5 "+3.3VA") (pintype "passive"))
  )
	(footprint "sdi-mipi-bridge-footprints:C_0402_1005Metric" (layer "B.Cu")
    (at 116.5 118.4 90)
    (descr "Capacitor SMD 0402")
    (tags "capacitor SMD 0402")
    (property "Author" "Antmicro")
    (property "Dielectric" "X7R")
    (property "License" "Apache-2.0")
    (property "MPN" "GRM155R71H103KA88D")
    (property "Manufacturer" "Murata")
    (property "Sheetfile" "sdi-mipi-bridge.kicad_sch")
    (property "Sheetname" "")
    (property "Val" "10n")
    (property "Voltage" "50V")
    (property "ki_description" " ")
    (attr smd)
    (fp_text reference "C17" (at -1 1.3 90) (layer "B.SilkS")
        (effects (font (size 0.7 0.7) (thickness 0.15)) (justify right bottom mirror))
    )
    (fp_text value "C_10n_0402" (at 0 -1.4 90) (layer "B.Fab") hide
        (effects (font (size 0.7 0.7) (thickness 0.15)) (justify right bottom mirror))
    )
    (fp_text user "${REFERENCE}" (at -0.932 -3.168 90) (layer "B.Fab") hide
        (effects (font (size 0.7 0.7) (thickness 0.15)) (justify right bottom mirror))
    )
    (fp_text user "Author: Antmicro" (at -0.932 -4.17 90) (layer "B.Fab") hide
        (effects (font (size 0.7 0.7) (thickness 0.15)) (justify right bottom mirror))
    )
    (fp_text user "License: Apache-2.0" (at -0.932 -5.17 90) (layer "B.Fab") hide
        (effects (font (size 0.7 0.7) (thickness 0.15)) (justify right bottom mirror))
    )
    (fp_rect (start -0.94 0.47) (end 0.94 -0.47)
      (stroke (width 0.05) (type solid)) (fill none) (layer "B.CrtYd"))
    (fp_rect (start -0.499 0.249) (end 0.499 -0.249)
      (stroke (width 0.15) (type solid)) (fill none) (layer "B.Fab"))
    (pad "1" smd roundrect (at -0.484 0 90) (size 0.59 0.64) (layers "B.Cu" "B.Paste" "B.Mask") (roundrect_rratio 0.25)
      (net 3 "GNDA") (pintype "passive"))
    (pad "2" smd roundrect (at 0.484 0 90) (size 0.59 0.64) (layers "B.Cu" "B.Paste" "B.Mask") (roundrect_rratio 0.25)
      (net 5 "+3.3VA") (pintype "passive"))
  )
	(footprint "sdi-mipi-bridge-footprints:C_0402_1005Metric" (layer "B.Cu")
    (at 125.5 110.9 -90)
    (descr "Capacitor SMD 0402")
    (tags "capacitor SMD 0402")
    (property "Author" "Antmicro")
    (property "Dielectric" "")
    (property "License" "Apache-2.0")
    (property "MPN" "C1005X6S1A105K050BC")
    (property "Manufacturer" "TDK")
    (property "Sheetfile" "sdi-mipi-bridge.kicad_sch")
    (property "Sheetname" "")
    (property "Val" "1u")
    (property "Voltage" "")
    (property "ki_description" " ")
    (attr smd)
    (fp_text reference "C35" (at 0.9 -0.3 90) (layer "B.SilkS")
        (effects (font (size 0.7 0.7) (thickness 0.15)) (justify left bottom mirror))
    )
    (fp_text value "C_1u_0402" (at 0 -1.4 90) (layer "B.Fab") hide
        (effects (font (size 0.7 0.7) (thickness 0.15)) (justify left bottom mirror))
    )
    (fp_text user "Author: Antmicro" (at -0.932 -4.17 90) (layer "B.Fab") hide
        (effects (font (size 0.7 0.7) (thickness 0.15)) (justify left bottom mirror))
    )
    (fp_text user "License: Apache-2.0" (at -0.932 -5.17 90) (layer "B.Fab") hide
        (effects (font (size 0.7 0.7) (thickness 0.15)) (justify left bottom mirror))
    )
    (fp_text user "${REFERENCE}" (at -0.932 -3.168 90) (layer "B.Fab") hide
        (effects (font (size 0.7 0.7) (thickness 0.15)) (justify left bottom mirror))
    )
    (fp_rect (start -0.94 0.47) (end 0.94 -0.47)
      (stroke (width 0.05) (type solid)) (fill none) (layer "B.CrtYd"))
    (fp_rect (start -0.499 0.249) (end 0.499 -0.249)
      (stroke (width 0.15) (type solid)) (fill none) (layer "B.Fab"))
    (pad "1" smd roundrect (at -0.484 0 270) (size 0.59 0.64) (layers "B.Cu" "B.Paste" "B.Mask") (roundrect_rratio 0.25)
      (net 1 "GNDREF") (pintype "passive"))
    (pad "2" smd roundrect (at 0.484 0 270) (size 0.59 0.64) (layers "B.Cu" "B.Paste" "B.Mask") (roundrect_rratio 0.25)
      (net 76 "IO_VDD") (pintype "passive"))
  )
	(footprint "sdi-mipi-bridge-footprints:R_0402_1005Metric" (layer "B.Cu")
    (at 120 110.9 90)
    (descr "Resistor SMD 0402")
    (tags "resistor SMD 0402")
    (property "Author" "Antmicro")
    (property "License" "Apache-2.0")
    (property "MPN" "CR0402-FX-1050GLF")
    (property "Manufacturer" "Bourns")
    (property "Sheetfile" "sdi-mipi-bridge.kicad_sch")
    (property "Sheetname" "")
    (property "Tolerance" "1%")
    (property "Val" "105R")
    (property "ki_description" "105R resistor in 0402 package with 1% tolerance")
    (attr smd)
    (fp_text reference "R30" (at 2.1 0.4 90) (layer "B.SilkS")
        (effects (font (size 0.7 0.7) (thickness 0.15)) (justify right bottom mirror))
    )
    (fp_text value "R_105R_0402" (at 0 -1.4 90) (layer "B.Fab") hide
        (effects (font (size 0.7 0.7) (thickness 0.15)) (justify right bottom mirror))
    )
    (fp_text user "Author: Antmicro" (at -0.95 -4.169 90) (layer "B.Fab") hide
        (effects (font (size 0.7 0.7) (thickness 0.15)) (justify right bottom mirror))
    )
    (fp_text user "${REFERENCE}" (at -0.95 -3.168 90) (layer "B.Fab") hide
        (effects (font (size 0.7 0.7) (thickness 0.15)) (justify right bottom mirror))
    )
    (fp_text user "License: Apache-2.0" (at -0.95 -5.169 90) (layer "B.Fab") hide
        (effects (font (size 0.7 0.7) (thickness 0.15)) (justify right bottom mirror))
    )
    (fp_rect (start -0.93 0.47) (end 0.93 -0.47)
      (stroke (width 0.05) (type solid)) (fill none) (layer "B.CrtYd"))
    (fp_rect (start -0.5 0.25) (end 0.5 -0.25)
      (stroke (width 0.15) (type solid)) (fill none) (layer "B.Fab"))
    (pad "1" smd roundrect (at -0.485 0 90) (size 0.59 0.64) (layers "B.Cu" "B.Paste" "B.Mask") (roundrect_rratio 0.25)
      (net 4 "VPP") (pintype "passive"))
    (pad "2" smd roundrect (at 0.485 0 90) (size 0.59 0.64) (layers "B.Cu" "B.Paste" "B.Mask") (roundrect_rratio 0.25)
      (net 78 "VCO_VDD") (pintype "passive"))
  )
	(footprint "sdi-mipi-bridge-footprints:C_0603_1608Metric" (layer "B.Cu")
    (at 121.25 110.85 -90)
    (descr "Capacitor SMD 0603")
    (tags "capacitor 0603")
    (property "Author" "Antmicro")
    (property "Dielectric" "")
    (property "License" "Apache-2.0")
    (property "MPN" "F980G336MMA")
    (property "Manufacturer" "AVX")
    (property "Sheetfile" "sdi-mipi-bridge.kicad_sch")
    (property "Sheetname" "")
    (property "Val" "33u")
    (property "Voltage" "")
    (property "ki_description" " ")
    (attr smd)
    (fp_text reference "C58" (at -4.25 -0.35 90) (layer "B.SilkS")
        (effects (font (size 0.7 0.7) (thickness 0.15)) (justify left bottom mirror))
    )
    (fp_text value "C_33u_0603" (at 0 -1.6 90) (layer "B.Fab") hide
        (effects (font (size 0.7 0.7) (thickness 0.15)) (justify left bottom mirror))
    )
    (fp_text user "License: Apache-2.0" (at -1.682 -5.895 90) (layer "B.Fab") hide
        (effects (font (size 0.7 0.7) (thickness 0.15)) (justify left bottom mirror))
    )
    (fp_text user "Author: Antmicro" (at -1.682 -4.894 90) (layer "B.Fab") hide
        (effects (font (size 0.7 0.7) (thickness 0.15)) (justify left bottom mirror))
    )
    (fp_text user "${REFERENCE}" (at -1.682 -3.895 90) (layer "B.Fab") hide
        (effects (font (size 0.7 0.7) (thickness 0.15)) (justify left bottom mirror))
    )
    (fp_line (start -0.3 -0.3) (end 0.3 -0.3)
      (stroke (width 0.15) (type solid)) (layer "B.SilkS"))
    (fp_line (start -0.3 0.3) (end 0.3 0.3)
      (stroke (width 0.15) (type solid)) (layer "B.SilkS"))
    (fp_rect (start -1.24 0.7) (end 1.24 -0.7)
      (stroke (width 0.05) (type solid)) (fill none) (layer "B.CrtYd"))
    (fp_rect (start -0.8 0.4) (end 0.8 -0.4)
      (stroke (width 0.15) (type solid)) (fill none) (layer "B.Fab"))
    (pad "1" smd roundrect (at -0.7 0 270) (size 0.6 0.8) (layers "B.Cu" "B.Paste" "B.Mask") (roundrect_rratio 0.2)
      (net 78 "VCO_VDD") (pintype "passive"))
    (pad "2" smd roundrect (at 0.7 0 270) (size 0.6 0.8) (layers "B.Cu" "B.Paste" "B.Mask") (roundrect_rratio 0.2)
      (net 3 "GNDA") (pintype "passive"))
  )
	(footprint "sdi-mipi-bridge-footprints:C_0402_1005Metric" (layer "B.Cu")
    (at 145.465 109.525 -90)
    (descr "Capacitor SMD 0402")
    (tags "capacitor SMD 0402")
    (property "Author" "Antmicro")
    (property "Dielectric" "")
    (property "License" "Apache-2.0")
    (property "MPN" "C1005X5R1A225K050BC")
    (property "Manufacturer" "TDK")
    (property "Sheetfile" "sdi-mipi-bridge.kicad_sch")
    (property "Sheetname" "")
    (property "Val" "2u2")
    (property "Voltage" "")
    (property "ki_description" " ")
    (attr smd)
    (fp_text reference "C37" (at -5.124 3.3825 90) (layer "B.SilkS")
        (effects (font (size 0.7 0.7) (thickness 0.15)) (justify left bottom mirror))
    )
    (fp_text value "C_2u2_0402" (at 0 -1.4 90) (layer "B.Fab") hide
        (effects (font (size 0.7 0.7) (thickness 0.15)) (justify left bottom mirror))
    )
    (fp_text user "Author: Antmicro" (at -0.932 -4.17 90) (layer "B.Fab") hide
        (effects (font (size 0.7 0.7) (thickness 0.15)) (justify left bottom mirror))
    )
    (fp_text user "${REFERENCE}" (at -0.932 -3.168 90) (layer "B.Fab") hide
        (effects (font (size 0.7 0.7) (thickness 0.15)) (justify left bottom mirror))
    )
    (fp_text user "License: Apache-2.0" (at -0.932 -5.17 90) (layer "B.Fab") hide
        (effects (font (size 0.7 0.7) (thickness 0.15)) (justify left bottom mirror))
    )
    (fp_rect (start -0.94 0.47) (end 0.94 -0.47)
      (stroke (width 0.05) (type solid)) (fill none) (layer "B.CrtYd"))
    (fp_rect (start -0.499 0.249) (end 0.499 -0.249)
      (stroke (width 0.15) (type solid)) (fill none) (layer "B.Fab"))
    (pad "1" smd roundrect (at -0.484 0 270) (size 0.59 0.64) (layers "B.Cu" "B.Paste" "B.Mask") (roundrect_rratio 0.25)
      (net 1 "GNDREF") (pintype "passive"))
    (pad "2" smd roundrect (at 0.484 0 270) (size 0.59 0.64) (layers "B.Cu" "B.Paste" "B.Mask") (roundrect_rratio 0.25)
      (net 79 "VCC_IO") (pintype "passive"))
  )
	(footprint "sdi-mipi-bridge-footprints:C_0402_1005Metric" (layer "B.Cu")
    (at 142 112.23 90)
    (descr "Capacitor SMD 0402")
    (tags "capacitor SMD 0402")
    (property "Author" "Antmicro")
    (property "Dielectric" "")
    (property "License" "Apache-2.0")
    (property "MPN" "C1005X5R1A225K050BC")
    (property "Manufacturer" "TDK")
    (property "Sheetfile" "sdi-mipi-bridge.kicad_sch")
    (property "Sheetname" "")
    (property "Val" "2u2")
    (property "Voltage" "")
    (property "ki_description" " ")
    (attr smd)
    (fp_text reference "C38" (at -0.97 -0.6 90) (layer "B.SilkS")
        (effects (font (size 0.7 0.7) (thickness 0.15)) (justify right bottom mirror))
    )
    (fp_text value "C_2u2_0402" (at 0 -1.4 90) (layer "B.Fab") hide
        (effects (font (size 0.7 0.7) (thickness 0.15)) (justify right bottom mirror))
    )
    (fp_text user "Author: Antmicro" (at -0.932 -4.17 90) (layer "B.Fab") hide
        (effects (font (size 0.7 0.7) (thickness 0.15)) (justify right bottom mirror))
    )
    (fp_text user "${REFERENCE}" (at -0.932 -3.168 90) (layer "B.Fab") hide
        (effects (font (size 0.7 0.7) (thickness 0.15)) (justify right bottom mirror))
    )
    (fp_text user "License: Apache-2.0" (at -0.932 -5.17 90) (layer "B.Fab") hide
        (effects (font (size 0.7 0.7) (thickness 0.15)) (justify right bottom mirror))
    )
    (fp_rect (start -0.94 0.47) (end 0.94 -0.47)
      (stroke (width 0.05) (type solid)) (fill none) (layer "B.CrtYd"))
    (fp_rect (start -0.499 0.249) (end 0.499 -0.249)
      (stroke (width 0.15) (type solid)) (fill none) (layer "B.Fab"))
    (pad "1" smd roundrect (at -0.484 0 90) (size 0.59 0.64) (layers "B.Cu" "B.Paste" "B.Mask") (roundrect_rratio 0.25)
      (net 1 "GNDREF") (pintype "passive"))
    (pad "2" smd roundrect (at 0.484 0 90) (size 0.59 0.64) (layers "B.Cu" "B.Paste" "B.Mask") (roundrect_rratio 0.25)
      (net 77 "VCCA_DPHY") (pintype "passive"))
  )
	(footprint "sdi-mipi-bridge-footprints:C_0402_1005Metric" (layer "B.Cu")
    (at 148.99 118.87 90)
    (descr "Capacitor SMD 0402")
    (tags "capacitor SMD 0402")
    (property "Author" "Antmicro")
    (property "Dielectric" "")
    (property "License" "Apache-2.0")
    (property "MPN" "0402X104K6R3CT")
    (property "Manufacturer" "Walsin")
    (property "Sheetfile" "sdi-mipi-bridge.kicad_sch")
    (property "Sheetname" "")
    (property "Val" "100n")
    (property "Voltage" "")
    (property "ki_description" " ")
    (attr smd)
    (fp_text reference "C48" (at -6.73 9.21 90) (layer "B.SilkS")
        (effects (font (size 0.7 0.7) (thickness 0.15)) (justify left bottom mirror))
    )
    (fp_text value "C_100n_6V3_0402" (at 0 -1.4 90) (layer "B.Fab") hide
        (effects (font (size 0.7 0.7) (thickness 0.15)) (justify right bottom mirror))
    )
    (fp_text user "${REFERENCE}" (at -0.932 -3.168 90) (layer "B.Fab") hide
        (effects (font (size 0.7 0.7) (thickness 0.15)) (justify right bottom mirror))
    )
    (fp_text user "Author: Antmicro" (at -0.932 -4.17 90) (layer "B.Fab") hide
        (effects (font (size 0.7 0.7) (thickness 0.15)) (justify right bottom mirror))
    )
    (fp_text user "License: Apache-2.0" (at -0.932 -5.17 90) (layer "B.Fab") hide
        (effects (font (size 0.7 0.7) (thickness 0.15)) (justify right bottom mirror))
    )
    (fp_rect (start -0.94 0.47) (end 0.94 -0.47)
      (stroke (width 0.05) (type solid)) (fill none) (layer "B.CrtYd"))
    (fp_rect (start -0.499 0.249) (end 0.499 -0.249)
      (stroke (width 0.15) (type solid)) (fill none) (layer "B.Fab"))
    (pad "1" smd roundrect (at -0.484 0 90) (size 0.59 0.64) (layers "B.Cu" "B.Paste" "B.Mask") (roundrect_rratio 0.25)
      (net 1 "GNDREF") (pintype "passive"))
    (pad "2" smd roundrect (at 0.484 0 90) (size 0.59 0.64) (layers "B.Cu" "B.Paste" "B.Mask") (roundrect_rratio 0.25)
      (net 2 "+1V2") (pintype "passive"))
  )
	(footprint "sdi-mipi-bridge-footprints:C_0402_1005Metric" (layer "B.Cu")
    (at 148.95 112.94 -90)
    (descr "Capacitor SMD 0402")
    (tags "capacitor SMD 0402")
    (property "Author" "Antmicro")
    (property "Dielectric" "")
    (property "License" "Apache-2.0")
    (property "MPN" "C1005X6S1A105K050BC")
    (property "Manufacturer" "TDK")
    (property "Sheetfile" "sdi-mipi-bridge.kicad_sch")
    (property "Sheetname" "")
    (property "Val" "1u")
    (property "Voltage" "")
    (property "ki_description" " ")
    (attr smd)
    (fp_text reference "C45" (at 6.66 -9.25 90) (layer "B.SilkS")
        (effects (font (size 0.7 0.7) (thickness 0.15)) (justify left bottom mirror))
    )
    (fp_text value "C_1u_0402" (at 0 -1.4 90) (layer "B.Fab") hide
        (effects (font (size 0.7 0.7) (thickness 0.15)) (justify left bottom mirror))
    )
    (fp_text user "License: Apache-2.0" (at -0.932 -5.17 90) (layer "B.Fab") hide
        (effects (font (size 0.7 0.7) (thickness 0.15)) (justify left bottom mirror))
    )
    (fp_text user "Author: Antmicro" (at -0.932 -4.17 90) (layer "B.Fab") hide
        (effects (font (size 0.7 0.7) (thickness 0.15)) (justify left bottom mirror))
    )
    (fp_text user "${REFERENCE}" (at -0.932 -3.168 90) (layer "B.Fab") hide
        (effects (font (size 0.7 0.7) (thickness 0.15)) (justify left bottom mirror))
    )
    (fp_rect (start -0.94 0.47) (end 0.94 -0.47)
      (stroke (width 0.05) (type solid)) (fill none) (layer "B.CrtYd"))
    (fp_rect (start -0.499 0.249) (end 0.499 -0.249)
      (stroke (width 0.15) (type solid)) (fill none) (layer "B.Fab"))
    (pad "1" smd roundrect (at -0.484 0 270) (size 0.59 0.64) (layers "B.Cu" "B.Paste" "B.Mask") (roundrect_rratio 0.25)
      (net 1 "GNDREF") (pintype "passive"))
    (pad "2" smd roundrect (at 0.484 0 270) (size 0.59 0.64) (layers "B.Cu" "B.Paste" "B.Mask") (roundrect_rratio 0.25)
      (net 141 "Net-(C45-Pad2)") (pintype "passive"))
  )
)
